(kicad_pcb
	(version 20260206)
	(generator "pcbnew")
	(generator_version "10.0")
	(general
		(thickness 1.6)
		(legacy_teardrops no)
	)
	(paper "A4")
	(title_block
		(title "03242023_DA0F0TMBIJ0_F0T_Motherboard_J_brd_V01_OCP.brd")
		(comment 1 "Grand Teton / footprint 1682 of 6105 (U1), pads 2255-2362 of 4677")
	)
	(layers
		(0 "F.Cu" signal "TOP")
		(4 "In1.Cu" signal "GND")
		(6 "In2.Cu" signal "IN1")
		(8 "In3.Cu" signal "GND1")
		(10 "In4.Cu" signal "IN2")
		(12 "In5.Cu" signal "GND2")
		(14 "In6.Cu" signal "IN3")
		(16 "In7.Cu" signal "GND3")
		(18 "In8.Cu" signal "VCC")
		(20 "In9.Cu" signal "VCC1")
		(22 "In10.Cu" signal "GND4")
		(24 "In11.Cu" signal "IN4")
		(26 "In12.Cu" signal "GND5")
		(28 "In13.Cu" signal "IN5")
		(30 "In14.Cu" signal "GND6")
		(32 "In15.Cu" signal "IN6")
		(34 "In16.Cu" signal "GND7")
		(2 "B.Cu" signal "BOTTOM")
		(9 "F.Adhes" user "F.Adhesive")
		(11 "B.Adhes" user "B.Adhesive")
		(13 "F.Paste" user "Package Geometry/Pastemask Top")
		(15 "B.Paste" user "Package Geometry/Pastemask Bottom")
		(5 "F.SilkS" user "Ref Des/Silkscreen Top")
		(7 "B.SilkS" user "Ref Des/Silkscreen Bottom")
		(1 "F.Mask" user "Board Geometry/Soldermask Top")
		(3 "B.Mask" user "Board Geometry/Soldermask Bottom")
		(17 "Dwgs.User" user "User.Drawings")
		(19 "Cmts.User" user "User.Comments")
		(21 "Eco1.User" user "User.Eco1")
		(23 "Eco2.User" user "User.Eco2")
		(25 "Edge.Cuts" user "Board Geometry/Outline")
		(27 "Margin" user)
		(31 "F.CrtYd" user "Package Geometry/Place Bound Top")
		(29 "B.CrtYd" user "Package Geometry/Place Bound Bottom")
		(35 "F.Fab" user "Ref Des/Assembly Top")
		(33 "B.Fab" user "Ref Des/Assembly Bottom")
	)
	(footprint ""
		(layer "F.Cu")
		(at 111.93018 -251.76988 90)
		(property "Reference" "U1"
			(at -74.913236 41.548812 0)
			(unlocked yes)
			(layer "F.SilkS")
			(effects
				(font
					(size 1.6002 1.1938)
					(thickness 0.1524)
				)
				(justify left)
			)
		)
		(property "Value" ""
			(at 0 0 90)
			(layer "F.Fab")
			(effects
				(font
					(size 1.27 1.27)
				)
			)
		)
		(duplicate_pad_numbers_are_jumpers no)
		(pad "CV85" smd circle
			(at 32.541718 9.217914 270)
			(size 0.4318 0.4318)
			(layers "F.Cu" "F.Mask" "F.Paste")
			(net "P5E_CPU1_PE3_TX_DN<13>")
		)
		(pad "CV87" smd circle
			(at 34.169604 9.217914 270)
			(size 0.4318 0.4318)
			(layers "F.Cu" "F.Mask" "F.Paste")
			(net "GND")
		)
		(pad "CV89" smd circle
			(at 35.797236 9.217914 270)
			(size 0.4318 0.4318)
			(layers "F.Cu" "F.Mask" "F.Paste")
			(net "P5E_CPU1_PE3_RX_DN<14>")
		)
		(pad "CV91" smd oval
			(at 37.425122 9.217914)
			(size 0.381 0.4826)
			(drill
				(offset 0 -0.0508)
			)
			(layers "F.Cu" "F.Mask" "F.Paste")
			(net "GND")
		)
		(pad "CW1" smd oval
			(at -37.425122 9.578086 180)
			(size 0.381 0.4826)
			(drill
				(offset 0 -0.0508)
			)
			(layers "F.Cu" "F.Mask" "F.Paste")
			(net "GND")
		)
		(pad "CW3" smd circle
			(at -35.797236 9.578086 270)
			(size 0.4318 0.4318)
			(layers "F.Cu" "F.Mask" "F.Paste")
			(net "UPI_CPU0_CPU1_P0P1_DP<14>")
		)
		(pad "CW5" smd circle
			(at -34.169604 9.578086 270)
			(size 0.4318 0.4318)
			(layers "F.Cu" "F.Mask" "F.Paste")
			(net "GND")
		)
		(pad "CW7" smd circle
			(at -32.541718 9.578086 270)
			(size 0.4318 0.4318)
			(layers "F.Cu" "F.Mask" "F.Paste")
			(net "UPI_CPU1_CPU0_P1P0_DP<13>")
		)
		(pad "CW9" smd circle
			(at -30.914086 9.578086 270)
			(size 0.4318 0.4318)
			(layers "F.Cu" "F.Mask" "F.Paste")
			(net "GND")
		)
		(pad "CW11" smd circle
			(at -29.2862 9.578086 270)
			(size 0.4318 0.4318)
			(layers "F.Cu" "F.Mask" "F.Paste")
			(net "P5E_CPU1_PE2_RX_DP<1>")
		)
		(pad "CW13" smd circle
			(at -27.658314 9.578086 270)
			(size 0.4318 0.4318)
			(layers "F.Cu" "F.Mask" "F.Paste")
			(net "GND")
		)
		(pad "CW15" smd circle
			(at -26.030682 9.578086 270)
			(size 0.4318 0.4318)
			(layers "F.Cu" "F.Mask" "F.Paste")
			(net "P5E_CPU1_PE2_TX_DP<1>")
		)
		(pad "CW17" smd circle
			(at -24.402796 9.578086 270)
			(size 0.4318 0.4318)
			(layers "F.Cu" "F.Mask" "F.Paste")
			(net "GND")
		)
		(pad "CW19" smd circle
			(at -22.77491 9.578086 270)
			(size 0.4318 0.4318)
			(layers "F.Cu" "F.Mask" "F.Paste")
			(net "PU_CPU1_UPI1_AC_COUPLING")
		)
		(pad "CW21" smd circle
			(at -21.147278 9.578086 270)
			(size 0.4318 0.4318)
			(layers "F.Cu" "F.Mask" "F.Paste")
			(net "TP_FM_IBL_SLPS5_CPU1_R_N")
		)
		(pad "CW23" smd circle
			(at -19.519392 9.578086 270)
			(size 0.4318 0.4318)
			(layers "F.Cu" "F.Mask" "F.Paste")
			(net "CPU1_RSVD<139>")
		)
		(pad "CW25" smd circle
			(at -17.89176 9.578086 270)
			(size 0.4318 0.4318)
			(layers "F.Cu" "F.Mask" "F.Paste")
			(net "CPU1_RSVD<140>")
		)
		(pad "CW27" smd circle
			(at -16.263874 9.578086 270)
			(size 0.4318 0.4318)
			(layers "F.Cu" "F.Mask" "F.Paste")
			(net "CLK_100M_DB2000_CPU1_BCLK3_DN")
		)
		(pad "CW29" smd circle
			(at -14.635988 9.578086 270)
			(size 0.4318 0.4318)
			(layers "F.Cu" "F.Mask" "F.Paste")
			(net "CLK_100M_DB2000_CPU1_BCLK1_DP")
		)
		(pad "CW31" smd circle
			(at -13.008356 9.578086 270)
			(size 0.4318 0.4318)
			(layers "F.Cu" "F.Mask" "F.Paste")
			(net "CLK_25M_NSSC_CPU1_DN")
		)
		(pad "CW33" smd circle
			(at -11.380724 9.578086 270)
			(size 0.4318 0.4318)
			(layers "F.Cu" "F.Mask" "F.Paste")
			(net "GND")
		)
		(pad "CW35" smd circle
			(at -9.752838 9.578086 270)
			(size 0.4318 0.4318)
			(layers "F.Cu" "F.Mask" "F.Paste")
			(net "PVCCD_HV_CPU1")
		)
		(pad "CW37" smd circle
			(at -8.124952 9.578086 270)
			(size 0.4318 0.4318)
			(layers "F.Cu" "F.Mask" "F.Paste")
			(net "PVCCD_HV_CPU1")
		)
		(pad "CW39" smd circle
			(at -6.49732 9.578086 270)
			(size 0.4318 0.4318)
			(layers "F.Cu" "F.Mask" "F.Paste")
			(net "H_CPU0_PMSYNC_CPU1")
		)
		(pad "CW41" smd circle
			(at -4.869434 9.578086 270)
			(size 0.4318 0.4318)
			(layers "F.Cu" "F.Mask" "F.Paste")
			(net "NC_CPU1_HBM1_VIEWDIG1")
		)
		(pad "CW43" smd circle
			(at -3.241802 9.578086 270)
			(size 0.4318 0.4318)
			(layers "F.Cu" "F.Mask" "F.Paste")
			(net "TP_CPU1_SPARE6")
		)
		(pad "CW45" smd circle
			(at -1.613916 9.578086 270)
			(size 0.4318 0.4318)
			(layers "F.Cu" "F.Mask" "F.Paste")
			(net "PWRGD_DRAMPWRGD_CPU1_GH_LVC1_R")
		)
		(pad "CW48" smd circle
			(at 2.427732 9.688068 270)
			(size 0.4318 0.4318)
			(layers "F.Cu" "F.Mask" "F.Paste")
			(net "M_F_CPU1_ALERT_N")
		)
		(pad "CW50" smd circle
			(at 4.055618 9.688068 270)
			(size 0.4318 0.4318)
			(layers "F.Cu" "F.Mask" "F.Paste")
			(net "M_G_CPU1_ALERT_N")
		)
		(pad "CW52" smd circle
			(at 5.68325 9.688068 270)
			(size 0.4318 0.4318)
			(layers "F.Cu" "F.Mask" "F.Paste")
			(net "PVCCD_HV_CPU1")
		)
		(pad "CW54" smd circle
			(at 7.311136 9.688068 270)
			(size 0.4318 0.4318)
			(layers "F.Cu" "F.Mask" "F.Paste")
			(net "PVCCD_HV_CPU1")
		)
		(pad "CW56" smd circle
			(at 8.939022 9.688068 270)
			(size 0.4318 0.4318)
			(layers "F.Cu" "F.Mask" "F.Paste")
			(net "PVCCD_HV_CPU1")
		)
		(pad "CW58" smd circle
			(at 10.566654 9.688068 270)
			(size 0.4318 0.4318)
			(layers "F.Cu" "F.Mask" "F.Paste")
			(net "NC_CPU1_VIEWPIN_GNR1")
		)
		(pad "CW60" smd circle
			(at 12.19454 9.688068 270)
			(size 0.4318 0.4318)
			(layers "F.Cu" "F.Mask" "F.Paste")
			(net "PU_CPU1_SOCKET_ID0")
		)
		(pad "CW62" smd circle
			(at 13.822426 9.688068 270)
			(size 0.4318 0.4318)
			(layers "F.Cu" "F.Mask" "F.Paste")
			(net "PVCCINFAON_CPU1")
		)
		(pad "CW64" smd circle
			(at 15.450058 9.688068 270)
			(size 0.4318 0.4318)
			(layers "F.Cu" "F.Mask" "F.Paste")
			(net "PVCCINFAON_CPU1")
		)
		(pad "CW66" smd circle
			(at 17.07769 9.688068 270)
			(size 0.4318 0.4318)
			(layers "F.Cu" "F.Mask" "F.Paste")
			(net "PVCCINFAON_CPU1")
		)
		(pad "CW68" smd circle
			(at 18.705576 9.688068 270)
			(size 0.4318 0.4318)
			(layers "F.Cu" "F.Mask" "F.Paste")
			(net "CPU1_RSVD<144>")
		)
		(pad "CW70" smd circle
			(at 20.333462 9.688068 270)
			(size 0.4318 0.4318)
			(layers "F.Cu" "F.Mask" "F.Paste")
			(net "GND")
		)
		(pad "CW72" smd circle
			(at 21.961094 9.688068 270)
			(size 0.4318 0.4318)
			(layers "F.Cu" "F.Mask" "F.Paste")
			(net "GND")
		)
		(pad "CW74" smd circle
			(at 23.58898 9.688068 270)
			(size 0.4318 0.4318)
			(layers "F.Cu" "F.Mask" "F.Paste")
			(net "Net_710")
		)
		(pad "CW76" smd circle
			(at 25.216612 9.688068 270)
			(size 0.4318 0.4318)
			(layers "F.Cu" "F.Mask" "F.Paste")
			(net "Net_745")
		)
		(pad "CW78" smd circle
			(at 26.844498 9.688068 270)
			(size 0.4318 0.4318)
			(layers "F.Cu" "F.Mask" "F.Paste")
			(net "GND")
		)
		(pad "CW80" smd circle
			(at 28.472384 9.688068 270)
			(size 0.4318 0.4318)
			(layers "F.Cu" "F.Mask" "F.Paste")
			(net "GND")
		)
		(pad "CW82" smd circle
			(at 30.100016 9.688068 270)
			(size 0.4318 0.4318)
			(layers "F.Cu" "F.Mask" "F.Paste")
			(net "GND")
		)
		(pad "CW84" smd circle
			(at 31.727902 9.688068 270)
			(size 0.4318 0.4318)
			(layers "F.Cu" "F.Mask" "F.Paste")
			(net "GND")
		)
		(pad "CW86" smd circle
			(at 33.355534 9.688068 270)
			(size 0.4318 0.4318)
			(layers "F.Cu" "F.Mask" "F.Paste")
			(net "P5E_CPU1_PE3_TX_DP<13>")
		)
		(pad "CW88" smd circle
			(at 34.98342 9.688068 270)
			(size 0.4318 0.4318)
			(layers "F.Cu" "F.Mask" "F.Paste")
			(net "GND")
		)
		(pad "CW90" smd circle
			(at 36.611306 9.688068 270)
			(size 0.4318 0.4318)
			(layers "F.Cu" "F.Mask" "F.Paste")
			(net "P5E_CPU1_PE3_RX_DP<14>")
		)
		(pad "CY2" smd circle
			(at -36.611306 10.047732 270)
			(size 0.4318 0.4318)
			(layers "F.Cu" "F.Mask" "F.Paste")
			(net "UPI_CPU0_CPU1_P0P1_DN<14>")
		)
		(pad "CY4" smd circle
			(at -34.98342 10.047732 270)
			(size 0.4318 0.4318)
			(layers "F.Cu" "F.Mask" "F.Paste")
			(net "GND")
		)
		(pad "CY6" smd circle
			(at -33.355534 10.047732 270)
			(size 0.4318 0.4318)
			(layers "F.Cu" "F.Mask" "F.Paste")
			(net "UPI_CPU1_CPU0_P1P0_DN<13>")
		)
		(pad "CY8" smd circle
			(at -31.727902 10.047732 270)
			(size 0.4318 0.4318)
			(layers "F.Cu" "F.Mask" "F.Paste")
			(net "GND")
		)
		(pad "CY10" smd circle
			(at -30.100016 10.047732 270)
			(size 0.4318 0.4318)
			(layers "F.Cu" "F.Mask" "F.Paste")
			(net "P5E_CPU1_PE2_RX_DN<1>")
		)
		(pad "CY12" smd circle
			(at -28.472384 10.047732 270)
			(size 0.4318 0.4318)
			(layers "F.Cu" "F.Mask" "F.Paste")
			(net "GND")
		)
		(pad "CY14" smd circle
			(at -26.844498 10.047732 270)
			(size 0.4318 0.4318)
			(layers "F.Cu" "F.Mask" "F.Paste")
			(net "P5E_CPU1_PE2_TX_DP<2>")
		)
		(pad "CY16" smd circle
			(at -25.216612 10.047732 270)
			(size 0.4318 0.4318)
			(layers "F.Cu" "F.Mask" "F.Paste")
			(net "GND")
		)
		(pad "CY18" smd circle
			(at -23.58898 10.047732 270)
			(size 0.4318 0.4318)
			(layers "F.Cu" "F.Mask" "F.Paste")
			(net "GND")
		)
		(pad "CY20" smd circle
			(at -21.961094 10.047732 270)
			(size 0.4318 0.4318)
			(layers "F.Cu" "F.Mask" "F.Paste")
			(net "FM_S3M_CPU1_CPLD_CRC_ERROR")
		)
		(pad "CY22" smd circle
			(at -20.333462 10.047732 270)
			(size 0.4318 0.4318)
			(layers "F.Cu" "F.Mask" "F.Paste")
			(net "PD_JTAG_CPU1_PLD_TCK")
		)
		(pad "CY24" smd circle
			(at -18.705576 10.047732 270)
			(size 0.4318 0.4318)
			(layers "F.Cu" "F.Mask" "F.Paste")
			(net "NC_CPU1_DDR45_VIEWDIG0")
		)
		(pad "CY26" smd circle
			(at -17.07769 10.047732 270)
			(size 0.4318 0.4318)
			(layers "F.Cu" "F.Mask" "F.Paste")
			(net "GND")
		)
		(pad "CY28" smd circle
			(at -15.450058 10.047732 270)
			(size 0.4318 0.4318)
			(layers "F.Cu" "F.Mask" "F.Paste")
			(net "CLK_100M_DB2000_CPU1_BCLK1_DN")
		)
		(pad "CY30" smd circle
			(at -13.822426 10.047732 270)
			(size 0.4318 0.4318)
			(layers "F.Cu" "F.Mask" "F.Paste")
			(net "GND")
		)
		(pad "CY32" smd circle
			(at -12.19454 10.047732 270)
			(size 0.4318 0.4318)
			(layers "F.Cu" "F.Mask" "F.Paste")
			(net "CLK_25M_NSSC_CPU1_DP")
		)
		(pad "CY34" smd circle
			(at -10.566654 10.047732 270)
			(size 0.4318 0.4318)
			(layers "F.Cu" "F.Mask" "F.Paste")
			(net "PVCCD_HV_CPU1")
		)
		(pad "CY36" smd circle
			(at -8.939022 10.047732 270)
			(size 0.4318 0.4318)
			(layers "F.Cu" "F.Mask" "F.Paste")
			(net "PVCCD_HV_CPU1")
		)
		(pad "CY38" smd circle
			(at -7.311136 10.047732 270)
			(size 0.4318 0.4318)
			(layers "F.Cu" "F.Mask" "F.Paste")
			(net "NC_CPU1_DDR45_VIEWDIG1")
		)
		(pad "CY40" smd circle
			(at -5.68325 10.047732 270)
			(size 0.4318 0.4318)
			(layers "F.Cu" "F.Mask" "F.Paste")
			(net "TP_H_CPU1_PMDOWN_PCH_R")
		)
		(pad "CY42" smd circle
			(at -4.055618 10.047732 270)
			(size 0.4318 0.4318)
			(layers "F.Cu" "F.Mask" "F.Paste")
			(net "RST_CPU1_DRAM_EF_N")
		)
		(pad "CY44" smd circle
			(at -2.427732 10.047732 270)
			(size 0.4318 0.4318)
			(layers "F.Cu" "F.Mask" "F.Paste")
			(net "PWRGD_DRAMPWRGD_CPU1_EF_LVC1_R")
		)
		(pad "CY47" smd circle
			(at 1.613916 10.157714 270)
			(size 0.4318 0.4318)
			(layers "F.Cu" "F.Mask" "F.Paste")
			(net "M_E_CPU1_ALERT_N")
		)
		(pad "CY49" smd circle
			(at 3.241802 10.157714 270)
			(size 0.4318 0.4318)
			(layers "F.Cu" "F.Mask" "F.Paste")
			(net "NC_CPU1_DDR67_VIEWDIG1")
		)
		(pad "CY51" smd circle
			(at 4.869434 10.157714 270)
			(size 0.4318 0.4318)
			(layers "F.Cu" "F.Mask" "F.Paste")
			(net "M_H_CPU1_ALERT_N")
		)
		(pad "CY53" smd circle
			(at 6.49732 10.157714 270)
			(size 0.4318 0.4318)
			(layers "F.Cu" "F.Mask" "F.Paste")
			(net "PVCCD_HV_CPU1")
		)
		(pad "CY55" smd circle
			(at 8.124952 10.157714 270)
			(size 0.4318 0.4318)
			(layers "F.Cu" "F.Mask" "F.Paste")
			(net "RST_CPU1_DRAM_GH_N")
		)
		(pad "CY57" smd circle
			(at 9.752838 10.157714 270)
			(size 0.4318 0.4318)
			(layers "F.Cu" "F.Mask" "F.Paste")
			(net "NC_CPU1_VIEWPIN_GNR3")
		)
		(pad "CY59" smd circle
			(at 11.380724 10.157714 270)
			(size 0.4318 0.4318)
			(layers "F.Cu" "F.Mask" "F.Paste")
			(net "PU_CPU1_LEGACY_SKT")
		)
		(pad "CY61" smd circle
			(at 13.008356 10.157714 270)
			(size 0.4318 0.4318)
			(layers "F.Cu" "F.Mask" "F.Paste")
			(net "PU_CPU1_SOCKET_ID1")
		)
		(pad "CY63" smd circle
			(at 14.635988 10.157714 270)
			(size 0.4318 0.4318)
			(layers "F.Cu" "F.Mask" "F.Paste")
			(net "GND")
		)
		(pad "CY65" smd circle
			(at 16.263874 10.157714 270)
			(size 0.4318 0.4318)
			(layers "F.Cu" "F.Mask" "F.Paste")
			(net "PVCCINFAON_CPU1")
		)
		(pad "CY67" smd circle
			(at 17.89176 10.157714 270)
			(size 0.4318 0.4318)
			(layers "F.Cu" "F.Mask" "F.Paste")
			(net "PVCCINFAON_CPU1")
		)
		(pad "CY69" smd circle
			(at 19.519392 10.157714 270)
			(size 0.4318 0.4318)
			(layers "F.Cu" "F.Mask" "F.Paste")
			(net "NC_UART_IBL_CPU1_RXD")
		)
		(pad "CY71" smd circle
			(at 21.147278 10.157714 270)
			(size 0.4318 0.4318)
			(layers "F.Cu" "F.Mask" "F.Paste")
			(net "NC_UART_IBL_CPU1_RTS")
		)
		(pad "CY73" smd circle
			(at 22.77491 10.157714 270)
			(size 0.4318 0.4318)
			(layers "F.Cu" "F.Mask" "F.Paste")
			(net "GND")
		)
		(pad "CY75" smd circle
			(at 24.402796 10.157714 270)
			(size 0.4318 0.4318)
			(layers "F.Cu" "F.Mask" "F.Paste")
			(net "PVCCFA_EHV_FIVRA_CPU1")
		)
		(pad "CY77" smd circle
			(at 26.030682 10.157714 270)
			(size 0.4318 0.4318)
			(layers "F.Cu" "F.Mask" "F.Paste")
			(net "GND")
		)
		(pad "CY79" smd circle
			(at 27.658314 10.157714 270)
			(size 0.4318 0.4318)
			(layers "F.Cu" "F.Mask" "F.Paste")
			(net "PVCCFA_EHV_FIVRA_CPU1")
		)
		(pad "CY81" smd circle
			(at 29.2862 10.157714 270)
			(size 0.4318 0.4318)
			(layers "F.Cu" "F.Mask" "F.Paste")
			(net "GND")
		)
		(pad "CY83" smd circle
			(at 30.914086 10.157714 270)
			(size 0.4318 0.4318)
			(layers "F.Cu" "F.Mask" "F.Paste")
			(net "GND")
		)
		(pad "CY85" smd circle
			(at 32.541718 10.157714 270)
			(size 0.4318 0.4318)
			(layers "F.Cu" "F.Mask" "F.Paste")
			(net "PVCCFA_EHV_FIVRA_CPU1")
		)
		(pad "CY87" smd circle
			(at 34.169604 10.157714 270)
			(size 0.4318 0.4318)
			(layers "F.Cu" "F.Mask" "F.Paste")
			(net "P5E_CPU1_PE3_TX_DN<12>")
		)
		(pad "CY89" smd circle
			(at 35.797236 10.157714 270)
			(size 0.4318 0.4318)
			(layers "F.Cu" "F.Mask" "F.Paste")
			(net "PVCCFA_EHV_FIVRA_CPU1")
		)
		(pad "CY91" smd oval
			(at 37.425122 10.157714)
			(size 0.381 0.4826)
			(drill
				(offset 0 -0.0508)
			)
			(layers "F.Cu" "F.Mask" "F.Paste")
			(net "P5E_CPU1_PE3_RX_DP<13>")
		)
		(pad "D4" smd oval
			(at -34.98342 -25.664414 135)
			(size 0.381 0.4826)
			(drill
				(offset 0 -0.0508)
			)
			(layers "F.Cu" "F.Mask" "F.Paste")
			(net "CPU1_RSVD<153>")
		)
		(pad "D6" smd oval
			(at -33.355534 -25.664414 135)
			(size 0.381 0.4826)
			(drill
				(offset 0 -0.0508)
			)
			(layers "F.Cu" "F.Mask" "F.Paste")
			(net "GND")
		)
		(pad "D8" smd oval
			(at -31.727902 -25.664414 135)
			(size 0.381 0.4826)
			(drill
				(offset 0 -0.0508)
			)
			(layers "F.Cu" "F.Mask" "F.Paste")
			(net "GND")
		)
		(pad "D10" smd circle
			(at -30.100016 -25.664414 270)
			(size 0.4318 0.4318)
			(layers "F.Cu" "F.Mask" "F.Paste")
			(net "GND")
		)
		(pad "D12" smd circle
			(at -28.472384 -25.664414 270)
			(size 0.4318 0.4318)
			(layers "F.Cu" "F.Mask" "F.Paste")
			(net "GND")
		)
		(pad "D14" smd circle
			(at -26.844498 -25.664414 270)
			(size 0.4318 0.4318)
			(layers "F.Cu" "F.Mask" "F.Paste")
			(net "GND")
		)
		(pad "D16" smd circle
			(at -25.216612 -25.664414 270)
			(size 0.4318 0.4318)
			(layers "F.Cu" "F.Mask" "F.Paste")
			(net "GND")
		)
		(pad "D18" smd circle
			(at -23.58898 -25.664414 270)
			(size 0.4318 0.4318)
			(layers "F.Cu" "F.Mask" "F.Paste")
			(net "GND")
		)
		(pad "D20" smd circle
			(at -21.961094 -25.664414 270)
			(size 0.4318 0.4318)
			(layers "F.Cu" "F.Mask" "F.Paste")
			(net "GND")
		)
		(pad "D22" smd circle
			(at -20.333462 -25.664414 270)
			(size 0.4318 0.4318)
			(layers "F.Cu" "F.Mask" "F.Paste")
			(net "GND")
		)
		(pad "D24" smd circle
			(at -18.705576 -25.664414 270)
			(size 0.4318 0.4318)
			(layers "F.Cu" "F.Mask" "F.Paste")
			(net "GND")
		)
		(pad "D26" smd circle
			(at -17.07769 -25.664414 270)
			(size 0.4318 0.4318)
			(layers "F.Cu" "F.Mask" "F.Paste")
			(net "GND")
		)
		(pad "D28" smd circle
			(at -15.450058 -25.664414 270)
			(size 0.4318 0.4318)
			(layers "F.Cu" "F.Mask" "F.Paste")
			(net "GND")
		)
		(pad "D30" smd circle
			(at -13.822426 -25.664414 270)
			(size 0.4318 0.4318)
			(layers "F.Cu" "F.Mask" "F.Paste")
			(net "GND")
		)
	)
)
